(kicad_pcb
	(version 20241229)
	(generator "pcbnew")
	(generator_version "9.0")
	(general
		(thickness 1.62)
		(legacy_teardrops no)
	)
	(paper "A3")
	(title_block
		(title "COM Express 7 Baseboard")
		(date "2025-02-04")
		(rev "1.1.2")
		(company "Antmicro Ltd")
		(comment 1 "www.antmicro.com")
		(comment 9 "footprints 64-67 of 802")
	)
	(layers
		(0 "F.Cu" signal)
		(4 "In1.Cu" signal)
		(6 "In2.Cu" signal)
		(8 "In3.Cu" signal)
		(10 "In4.Cu" signal)
		(12 "In5.Cu" signal)
		(14 "In6.Cu" signal)
		(2 "B.Cu" signal)
		(9 "F.Adhes" user "F.Adhesive")
		(11 "B.Adhes" user "B.Adhesive")
		(13 "F.Paste" user)
		(15 "B.Paste" user)
		(5 "F.SilkS" user "F.Silkscreen")
		(7 "B.SilkS" user "B.Silkscreen")
		(1 "F.Mask" user)
		(3 "B.Mask" user)
		(17 "Dwgs.User" user "User.Drawings")
		(19 "Cmts.User" user "User.Comments")
		(21 "Eco1.User" user "User.Eco1")
		(23 "Eco2.User" user "User.Eco2")
		(25 "Edge.Cuts" user)
		(27 "Margin" user)
		(31 "F.CrtYd" user "F.Courtyard")
		(29 "B.CrtYd" user "B.Courtyard")
		(35 "F.Fab" user)
		(33 "B.Fab" user)
	)
	(footprint "antmicro-footprints:R_0402_1005Metric"
		(layer "F.Cu")
		(at 156.15 84.06)
		(descr "Resistor SMD 0402")
		(tags "resistor SMD 0402")
		(property "Reference" "R136"
			(at -1.35 -0.5 0)
			(layer "F.SilkS")
			(effects
				(font
					(size 0.7 0.7)
					(thickness 0.15)
				)
				(justify left bottom)
			)
		)
		(property "Value" "R_10k_0402"
			(at -1.011843 1.772047 0)
			(layer "F.Fab")
			(effects
				(font
					(size 0.7 0.7)
					(thickness 0.15)
				)
				(justify left bottom)
			)
		)
		(property "Datasheet" "https://www.bourns.com/docs/product-datasheets/cr.pdf"
			(at 0 0 0)
			(layer "F.Fab")
			(hide yes)
			(effects
				(font
					(size 1.27 1.27)
					(thickness 0.15)
				)
			)
		)
		(property "Author" "Antmicro"
			(at 0 0 0)
			(layer "F.Fab")
			(hide yes)
			(effects
				(font
					(size 1 1)
					(thickness 0.15)
				)
			)
		)
		(property "License" "Apache-2.0"
			(at 0 0 0)
			(layer "F.Fab")
			(hide yes)
			(effects
				(font
					(size 1 1)
					(thickness 0.15)
				)
			)
		)
		(property "MPN" "CR0402-FX-1002GLF"
			(at 0 0 0)
			(layer "F.Fab")
			(hide yes)
			(effects
				(font
					(size 1 1)
					(thickness 0.15)
				)
			)
		)
		(property "Manufacturer" "Bourns"
			(at 0 0 0)
			(layer "F.Fab")
			(hide yes)
			(effects
				(font
					(size 1 1)
					(thickness 0.15)
				)
			)
		)
		(property "Public" "False"
			(at 0 0 0)
			(layer "F.Fab")
			(hide yes)
			(effects
				(font
					(size 1 1)
					(thickness 0.15)
				)
			)
		)
		(property "Tolerance" "1%"
			(at 0 0 0)
			(layer "F.Fab")
			(hide yes)
			(effects
				(font
					(size 1 1)
					(thickness 0.15)
				)
			)
		)
		(property "Val" "10k"
			(at 0 0 0)
			(layer "F.Fab")
			(hide yes)
			(effects
				(font
					(size 1 1)
					(thickness 0.15)
				)
			)
		)
		(sheetname "M.2 key E")
		(sheetfile "m2keye.kicad_sch")
		(attr smd)
		(fp_rect
			(start -0.925 -0.47)
			(end 0.925 0.47)
			(stroke
				(width 0.05)
				(type default)
			)
			(fill no)
			(layer "F.CrtYd")
		)
		(fp_rect
			(start -0.5 -0.25)
			(end 0.5 0.25)
			(stroke
				(width 0.15)
				(type solid)
			)
			(fill no)
			(layer "F.Fab")
		)
		(pad "1" smd roundrect
			(at -0.48 0)
			(size 0.59 0.64)
			(layers "F.Cu" "F.Mask" "F.Paste")
			(roundrect_rratio 0.25)
			(net 24 "/M.2 key E/~{CLKREQ}")
			(pintype "passive")
			(teardrops
				(best_length_ratio 0.2)
				(max_length 1)
				(best_width_ratio 0.9)
				(max_width 2)
				(curved_edges yes)
				(filter_ratio 0.9)
				(enabled yes)
				(allow_two_segments yes)
				(prefer_zone_connections yes)
			)
		)
		(pad "2" smd roundrect
			(at 0.48 0)
			(size 0.59 0.64)
			(layers "F.Cu" "F.Mask" "F.Paste")
			(roundrect_rratio 0.25)
			(net 2 "+3V3")
			(pintype "passive")
			(teardrops
				(best_length_ratio 0.2)
				(max_length 1)
				(best_width_ratio 0.9)
				(max_width 2)
				(curved_edges yes)
				(filter_ratio 0.9)
				(enabled yes)
				(allow_two_segments yes)
				(prefer_zone_connections yes)
			)
		)
	)
	(footprint "antmicro-footprints:PinHeader_1x3_P2.54mm_Drill1.1mm"
		(layer "F.Cu")
		(at 206.42 70.61)
		(property "Reference" "J14"
			(at -1.67 1.46 90)
			(layer "F.SilkS")
			(effects
				(font
					(size 0.7 0.7)
					(thickness 0.15)
				)
				(justify left bottom)
			)
		)
		(property "Value" "PinHeader_1x3_P2.54mm_Drill1.1mm"
			(at -1.6 2.7 0)
			(layer "F.Fab")
			(effects
				(font
					(size 0.7 0.7)
					(thickness 0.15)
				)
				(justify left bottom)
			)
		)
		(property "Datasheet" "https://katalog.we-online.de/em/datasheet/6130xx11121.pdf"
			(at 0 0 0)
			(layer "F.Fab")
			(hide yes)
			(effects
				(font
					(size 1.27 1.27)
					(thickness 0.15)
				)
			)
		)
		(property "Author" "Antmicro"
			(at 0 0 0)
			(layer "F.Fab")
			(hide yes)
			(effects
				(font
					(size 1 1)
					(thickness 0.15)
				)
			)
		)
		(property "License" "Apache-2.0"
			(at 0 0 0)
			(layer "F.Fab")
			(hide yes)
			(effects
				(font
					(size 1 1)
					(thickness 0.15)
				)
			)
		)
		(property "MPN" "61300311121"
			(at 0 0 0)
			(layer "F.Fab")
			(hide yes)
			(effects
				(font
					(size 1 1)
					(thickness 0.15)
				)
			)
		)
		(property "Manufacturer" "Würth Elektronik"
			(at 0 0 0)
			(layer "F.Fab")
			(hide yes)
			(effects
				(font
					(size 1 1)
					(thickness 0.15)
				)
			)
		)
		(sheetname "Com Express 7 MGMT")
		(sheetfile "com_express_7_mgmt.kicad_sch")
		(attr through_hole)
		(fp_line
			(start -1.401 -1.401)
			(end -1.401 -0.902)
			(stroke
				(width 0.15)
				(type solid)
			)
			(layer "F.SilkS")
		)
		(fp_line
			(start -1.401 -1.401)
			(end -0.902 -1.401)
			(stroke
				(width 0.15)
				(type solid)
			)
			(layer "F.SilkS")
		)
		(fp_line
			(start -1.401 1.398)
			(end -1.401 0.9)
			(stroke
				(width 0.15)
				(type solid)
			)
			(layer "F.SilkS")
		)
		(fp_line
			(start -1.401 1.398)
			(end -0.902 1.398)
			(stroke
				(width 0.15)
				(type solid)
			)
			(layer "F.SilkS")
		)
		(fp_line
			(start 6.499 -1.401)
			(end 5.999 -1.401)
			(stroke
				(width 0.15)
				(type solid)
			)
			(layer "F.SilkS")
		)
		(fp_line
			(start 6.499 -1.401)
			(end 6.499 -0.902)
			(stroke
				(width 0.15)
				(type solid)
			)
			(layer "F.SilkS")
		)
		(fp_line
			(start 6.499 1.398)
			(end 5.999 1.398)
			(stroke
				(width 0.15)
				(type solid)
			)
			(layer "F.SilkS")
		)
		(fp_line
			(start 6.499 1.398)
			(end 6.499 0.9)
			(stroke
				(width 0.15)
				(type solid)
			)
			(layer "F.SilkS")
		)
		(fp_line
			(start -1.52 -1.52)
			(end -1.52 1.5)
			(stroke
				(width 0.05)
				(type solid)
			)
			(layer "F.CrtYd")
		)
		(fp_line
			(start -1.52 -1.52)
			(end 6.58 -1.52)
			(stroke
				(width 0.05)
				(type solid)
			)
			(layer "F.CrtYd")
		)
		(fp_line
			(start -1.52 1.5)
			(end 6.58 1.5)
			(stroke
				(width 0.05)
				(type solid)
			)
			(layer "F.CrtYd")
		)
		(fp_line
			(start 6.58 -1.52)
			(end 6.58 1.5)
			(stroke
				(width 0.05)
				(type solid)
			)
			(layer "F.CrtYd")
		)
		(fp_line
			(start -1.27 -1.27)
			(end -1.27 1.269)
			(stroke
				(width 0.15)
				(type solid)
			)
			(layer "F.Fab")
		)
		(fp_line
			(start -1.27 -1.27)
			(end 6.349 -1.27)
			(stroke
				(width 0.15)
				(type solid)
			)
			(layer "F.Fab")
		)
		(fp_line
			(start -1.27 1.269)
			(end 6.349 1.269)
			(stroke
				(width 0.15)
				(type solid)
			)
			(layer "F.Fab")
		)
		(fp_line
			(start 6.349 -1.27)
			(end 6.349 1.269)
			(stroke
				(width 0.15)
				(type solid)
			)
			(layer "F.Fab")
		)
		(pad "1" thru_hole rect
			(at 0 0)
			(size 1.7 1.7)
			(drill 1.1)
			(layers "*.Cu" "*.Mask")
			(remove_unused_layers no)
			(net 524 "unconnected-(J14-Pad1)")
			(pintype "passive+no_connect")
			(teardrops
				(best_length_ratio 0.2)
				(max_length 1)
				(best_width_ratio 0.9)
				(max_width 2)
				(curved_edges yes)
				(filter_ratio 0.9)
				(enabled yes)
				(allow_two_segments yes)
				(prefer_zone_connections yes)
			)
		)
		(pad "2" thru_hole circle
			(at 2.539 0)
			(size 1.7 1.7)
			(drill 1.1)
			(layers "*.Cu" "*.Mask")
			(remove_unused_layers no)
			(net 525 "Net-(J14-Pad2)")
			(pintype "passive")
			(teardrops
				(best_length_ratio 0.4)
				(max_length 1)
				(best_width_ratio 0.9)
				(max_width 2)
				(curved_edges yes)
				(filter_ratio 0.9)
				(enabled yes)
				(allow_two_segments yes)
				(prefer_zone_connections yes)
			)
		)
		(pad "3" thru_hole circle
			(at 5.078 0)
			(size 1.7 1.7)
			(drill 1.1)
			(layers "*.Cu" "*.Mask")
			(remove_unused_layers no)
			(net 1 "GND")
			(pintype "passive")
			(teardrops
				(best_length_ratio 0.4)
				(max_length 1)
				(best_width_ratio 0.9)
				(max_width 2)
				(curved_edges yes)
				(filter_ratio 0.9)
				(enabled yes)
				(allow_two_segments yes)
				(prefer_zone_connections yes)
			)
		)
	)
	(footprint "antmicro-footprints:R_0402_1005Metric"
		(layer "F.Cu")
		(at 202.00239 83.347837 180)
		(descr "Resistor SMD 0402")
		(tags "resistor SMD 0402")
		(property "Reference" "R328"
			(at -1.275 -1.4 0)
			(layer "F.SilkS")
			(effects
				(font
					(size 0.7 0.7)
					(thickness 0.15)
				)
				(justify right bottom)
			)
		)
		(property "Value" "R_5k1_0402"
			(at -1.011843 1.772047 0)
			(layer "F.Fab")
			(effects
				(font
					(size 0.7 0.7)
					(thickness 0.15)
				)
				(justify right bottom)
			)
		)
		(property "Datasheet" "https://www.bourns.com/docs/product-datasheets/cr.pdf"
			(at 0 0 180)
			(layer "F.Fab")
			(hide yes)
			(effects
				(font
					(size 1.27 1.27)
					(thickness 0.15)
				)
			)
		)
		(property "Author" "Antmicro"
			(at 396.412 166.56 0)
			(layer "F.Fab")
			(hide yes)
			(effects
				(font
					(size 1 1)
					(thickness 0.15)
				)
			)
		)
		(property "License" "Apache-2.0"
			(at 396.412 166.56 0)
			(layer "F.Fab")
			(hide yes)
			(effects
				(font
					(size 1 1)
					(thickness 0.15)
				)
			)
		)
		(property "MPN" "CR0402-FX-5101GLF"
			(at 396.412 166.56 0)
			(layer "F.Fab")
			(hide yes)
			(effects
				(font
					(size 1 1)
					(thickness 0.15)
				)
			)
		)
		(property "Manufacturer" "Bourns"
			(at 396.412 166.56 0)
			(layer "F.Fab")
			(hide yes)
			(effects
				(font
					(size 1 1)
					(thickness 0.15)
				)
			)
		)
		(property "Tolerance" "1%"
			(at 396.412 166.56 0)
			(layer "F.Fab")
			(hide yes)
			(effects
				(font
					(size 1 1)
					(thickness 0.15)
				)
			)
		)
		(property "Val" "5k1"
			(at 396.412 166.56 0)
			(layer "F.Fab")
			(hide yes)
			(effects
				(font
					(size 1 1)
					(thickness 0.15)
				)
			)
		)
		(sheetname "Power")
		(sheetfile "power.kicad_sch")
		(attr smd)
		(fp_rect
			(start -0.925 -0.47)
			(end 0.925 0.47)
			(stroke
				(width 0.05)
				(type default)
			)
			(fill no)
			(layer "F.CrtYd")
		)
		(fp_rect
			(start -0.5 -0.25)
			(end 0.5 0.25)
			(stroke
				(width 0.15)
				(type solid)
			)
			(fill no)
			(layer "F.Fab")
		)
		(pad "1" smd roundrect
			(at -0.48 0 180)
			(size 0.59 0.64)
			(layers "F.Cu" "F.Mask" "F.Paste")
			(roundrect_rratio 0.25)
			(net 74 "+1V0")
			(pintype "passive")
			(teardrops
				(best_length_ratio 0.2)
				(max_length 1)
				(best_width_ratio 0.9)
				(max_width 2)
				(curved_edges yes)
				(filter_ratio 0.9)
				(enabled yes)
				(allow_two_segments yes)
				(prefer_zone_connections yes)
			)
		)
		(pad "2" smd roundrect
			(at 0.48 0 180)
			(size 0.59 0.64)
			(layers "F.Cu" "F.Mask" "F.Paste")
			(roundrect_rratio 0.25)
			(net 987 "Net-(Q13-B)")
			(pintype "passive")
			(teardrops
				(best_length_ratio 0.2)
				(max_length 1)
				(best_width_ratio 0.9)
				(max_width 2)
				(curved_edges yes)
				(filter_ratio 0.9)
				(enabled yes)
				(allow_two_segments yes)
				(prefer_zone_connections yes)
			)
		)
	)
	(footprint "antmicro-footprints:R_0805_2012Metric"
		(layer "F.Cu")
		(at 310.85 144.71 90)
		(property "Reference" "R85"
			(at -1.05 1.85 90)
			(layer "F.SilkS")
			(effects
				(font
					(size 0.7 0.7)
					(thickness 0.15)
				)
				(justify left bottom)
			)
		)
		(property "Value" "R_0R001_0805"
			(at 0 1.8 90)
			(layer "F.Fab")
			(effects
				(font
					(size 0.7 0.7)
					(thickness 0.15)
				)
				(justify left bottom)
			)
		)
		(property "Datasheet" "https://www.eaton.com/content/dam/eaton/products/electronic-components/resources/data-sheet/eaton-msma-automotive-smd-current-sense-resistor-metal-strip-data-sheet-elx1179.pdf"
			(at 0 0 90)
			(layer "F.Fab")
			(hide yes)
			(effects
				(font
					(size 1.27 1.27)
					(thickness 0.15)
				)
			)
		)
		(property "Author" "Antmicro"
			(at 455.56 -166.14 0)
			(layer "F.Fab")
			(hide yes)
			(effects
				(font
					(size 1 1)
					(thickness 0.15)
				)
			)
		)
		(property "License" "Apache-2.0"
			(at 455.56 -166.14 0)
			(layer "F.Fab")
			(hide yes)
			(effects
				(font
					(size 1 1)
					(thickness 0.15)
				)
			)
		)
		(property "MPN" "MSMA0805R0010FSM"
			(at 455.56 -166.14 0)
			(layer "F.Fab")
			(hide yes)
			(effects
				(font
					(size 1 1)
					(thickness 0.15)
				)
			)
		)
		(property "Manufacturer" "Eaton"
			(at 455.56 -166.14 0)
			(layer "F.Fab")
			(hide yes)
			(effects
				(font
					(size 1 1)
					(thickness 0.15)
				)
			)
		)
		(property "Public" "False"
			(at 455.56 -166.14 0)
			(layer "F.Fab")
			(hide yes)
			(effects
				(font
					(size 1 1)
					(thickness 0.15)
				)
			)
		)
		(property "Tolerance" "1%"
			(at 455.56 -166.14 0)
			(layer "F.Fab")
			(hide yes)
			(effects
				(font
					(size 1 1)
					(thickness 0.15)
				)
			)
		)
		(property "Val" "0R001"
			(at 455.56 -166.14 0)
			(layer "F.Fab")
			(hide yes)
			(effects
				(font
					(size 1 1)
					(thickness 0.15)
				)
			)
		)
		(sheetname "Power")
		(sheetfile "power.kicad_sch")
		(attr smd)
		(fp_line
			(start -0.3 -0.701)
			(end 0.298 -0.701)
			(stroke
				(width 0.15)
				(type solid)
			)
			(layer "F.SilkS")
		)
		(fp_line
			(start -0.32 0.699)
			(end 0.28 0.699)
			(stroke
				(width 0.15)
				(type solid)
			)
			(layer "F.SilkS")
		)
		(fp_rect
			(start 1.95 -0.9)
			(end -1.95 0.9)
			(stroke
				(width 0.05)
				(type default)
			)
			(fill no)
			(layer "F.CrtYd")
		)
		(fp_line
			(start -0.951 -0.682)
			(end 0.949 -0.682)
			(stroke
				(width 0.15)
				(type solid)
			)
			(layer "F.Fab")
		)
		(fp_line
			(start 0.949 -0.677)
			(end 0.949 0.675)
			(stroke
				(width 0.15)
				(type solid)
			)
			(layer "F.Fab")
		)
		(fp_line
			(start -0.951 -0.677)
			(end -0.951 0.675)
			(stroke
				(width 0.15)
				(type solid)
			)
			(layer "F.Fab")
		)
		(fp_line
			(start -0.951 0.68)
			(end 0.949 0.68)
			(stroke
				(width 0.15)
				(type solid)
			)
			(layer "F.Fab")
		)
		(pad "1" smd roundrect
			(at -1.1 0 90)
			(size 1.2 1.3)
			(layers "F.Cu" "F.Mask" "F.Paste")
			(roundrect_rratio 0.25)
			(net 145 "Net-(D24-C)")
			(pintype "passive")
			(teardrops
				(best_length_ratio 0.2)
				(max_length 1)
				(best_width_ratio 0.9)
				(max_width 2)
				(curved_edges yes)
				(filter_ratio 0.9)
				(enabled yes)
				(allow_two_segments yes)
				(prefer_zone_connections yes)
			)
		)
		(pad "2" smd roundrect
			(at 1.1 0 90)
			(size 1.2 1.3)
			(layers "F.Cu" "F.Mask" "F.Paste")
			(roundrect_rratio 0.25)
			(net 62 "+12V_AON")
			(pintype "passive")
			(teardrops
				(best_length_ratio 0.2)
				(max_length 1)
				(best_width_ratio 0.9)
				(max_width 2)
				(curved_edges yes)
				(filter_ratio 0.9)
				(enabled yes)
				(allow_two_segments yes)
				(prefer_zone_connections yes)
			)
		)
	)
)
